FILE_TYPE = CONNECTIVITY;
{Allegro Design Entry HDL 17.4-2019 S026 (4007227) 1/17/2022}
"PAGE_NUMBER" = 374;
0"NC";
1"GND\g";
2"P3V3_AUX\g";
3"P3V3_AUX\g";
4"P3V3_AUX\g";
5"GND\g";
6"GND\g";
7"GND\g";
8"P3V3_AUX\g";
9"P3V3_AUX\g";
10"GND\g";
11"P3V3_AUX\g";
12"P3V3_AUX\g";
13"GND\g";
14"GND\g";
15"LED_PWRGD_PVDDCR_CPU0_P0_D";
16"FM_LED_PWRGD_PVDD33_S5";
17"NC_Q83_S2";
18"NC_Q83_D2";
19"LED_PWRGD_PVDDCR_CPU1_P0_R";
20"FM_LED_PWRGD_PVDDIO_P0";
21"NC_Q83_G2";
22"FM_LED_PWRGD_PVDD18_S5_P0";
23"LED_PWRGD_PVDDCR_SOC_P0_R";
24"LED_PWRGD_PVDD11_S3_P0_D";
25"LED_PWRGD_PVDD18_S5_P0_R";
26"LED_PWRGD_PVDD18_S5_P0_D";
27"FM_LED_PWRGD_PVDD11_S3_P0";
28"LED_PWRGD_PVDD33_S5_R";
29"LED_PWRGD_PVDD11_S3_P0_R";
30"LED_PWRGD_PVDDIO_P0_D";
31"LED_PWRGD_PVDDIO_P0_R";
32"LED_PWRGD_PVDDCR_CPU0_P0_R";
33"LED_PWRGD_PVDDCR_SOC_P0_D";
34"FM_LED_PWRGD_PVDDCR_CPU1_P0";
35"LED_PWRGD_PVDDCR_CPU1_P0_D";
36"FM_LED_PWRGD_PVDDCR_CPU0_P0";
37"FM_LED_PWRGD_PVDDCR_SOC_P0";
38"LED_PWRGD_PVDD33_S5_D";
%"UNIVERSAL_GND"
"1","(-7925,5100)","0","pure_quanta_power","I10";
;
CDS_LIB"pure_quanta_power"
HDL_POWER"GND";
"A"1;
%"Q_LED"
"1","(-6900,1850)","2","pure_quanta","I11";
;
LOCATION"D76"
$SEC"1"
CDS_SEC"1"
MANUF_PN"LTST-C281TBKT-5A"
MATERIAL"IC"
PACK_TYPE"SMLF"
COLOR"LED_BLUE"
CDS_LIB"pure_quanta"
NEEDS_NO_SIZE"TRUE"
PART_NUMBER"BEBL0172Z00";
"A"
$PN"A"19;
"C"
$PN"C"35;
%"Q_RES"
"1","(-5525,1850)","0","pure_quanta","I12";
;
LOCATION"R3088"
$SEC"1"
CDS_SEC"1"
VALUE"130"
TOLERANCE"1%"
MATERIAL"CHIP"
WATTAGE"1/16W"
PACK_TYPE"0402LF"
CDS_LIB"pure_quanta"
PART_NUMBER"CS11302FB03";
"B"
$PN"2"2;
"A"
$PN"1"19;
%"Q_LED"
"1","(-6900,3175)","2","pure_quanta","I13";
;
LOCATION"D75"
$SEC"1"
CDS_SEC"1"
PACK_TYPE"SMLF"
MATERIAL"IC"
COLOR"LED_BLUE"
MANUF_PN"LTST-C281TBKT-5A"
CDS_LIB"pure_quanta"
NEEDS_NO_SIZE"TRUE"
PART_NUMBER"BEBL0172Z00";
"A"
$PN"A"23;
"C"
$PN"C"33;
%"Q_LED"
"1","(-6900,4400)","2","pure_quanta","I14";
;
LOCATION"D74"
$SEC"1"
CDS_SEC"1"
MANUF_PN"LTST-C281TBKT-5A"
PACK_TYPE"SMLF"
COLOR"LED_BLUE"
MATERIAL"IC"
CDS_LIB"pure_quanta"
NEEDS_NO_SIZE"TRUE"
PART_NUMBER"BEBL0172Z00";
"A"
$PN"A"32;
"C"
$PN"C"15;
%"Q_RES"
"1","(-5475,3175)","0","pure_quanta","I15";
;
LOCATION"R3089"
$SEC"1"
CDS_SEC"1"
MATERIAL"CHIP"
TOLERANCE"1%"
VALUE"130"
PACK_TYPE"0402LF"
WATTAGE"1/16W"
CDS_LIB"pure_quanta"
PART_NUMBER"CS11302FB03";
"B"
$PN"2"3;
"A"
$PN"1"23;
%"Q_RES"
"1","(-5525,4400)","0","pure_quanta","I16";
;
LOCATION"R3087"
$SEC"1"
CDS_SEC"1"
PACK_TYPE"0402LF"
MATERIAL"CHIP"
WATTAGE"1/16W"
TOLERANCE"1%"
VALUE"130"
CDS_LIB"pure_quanta"
PART_NUMBER"CS11302FB03";
"B"
$PN"2"4;
"A"
$PN"1"32;
%"MOSFET_NCH_DUAL"
"1","(-7975,5450)","0","pure_quanta","I18";
;
LOCATION"Q79"
$SEC"1"
CDS_SEC"1"
MATERIAL"IC"
PART_TYPE"SMLF"
VALUE"PJT138K"
CDS_LIB"pure_quanta"
CDS_LMAN_SYM_OUTLINE"-150,150,150,-150"
NEEDS_NO_SIZE"TRUE"
PART_NUMBER"BAM138K0003";
"D1"
$PN"6"38;
"G1"
$PN"2"16;
"S1"
$PN"1"1;
%"Q_LED"
"1","(-6900,5725)","2","pure_quanta","I19";
;
LOCATION"D73"
$SEC"1"
CDS_SEC"1"
MATERIAL"IC"
MANUF_PN"LTST-C281TBKT-5A"
COLOR"LED_BLUE"
PACK_TYPE"SMLF"
NEEDS_NO_SIZE"TRUE"
CDS_LIB"pure_quanta"
PART_NUMBER"BEBL0172Z00";
"A"
$PN"A"28;
"C"
$PN"C"38;
%"Q_RES"
"1","(-5550,5725)","0","pure_quanta","I20";
;
LOCATION"R3086"
$SEC"1"
CDS_SEC"1"
MATERIAL"CHIP"
TOLERANCE"1%"
PACK_TYPE"0402LF"
WATTAGE"1/16W"
VALUE"130"
CDS_LIB"pure_quanta"
PART_NUMBER"CS11302FB03";
"B"
$PN"2"8;
"A"
$PN"1"28;
%"UNIVERSAL_POWER"
"1","(-4925,2000)","0","pure_quanta_power","I21";
;
HDL_POWER"P3V3_AUX"
CDS_LIB"pure_quanta_power";
"A"2;
%"MOSFET_NCH_DUAL"
"1","(-3200,2875)","0","pure_quanta","I23";
;
LOCATION"Q83"
$SEC"1"
CDS_SEC"1"
PART_TYPE"SMLF"
VALUE"PJT138K"
MATERIAL"IC"
CDS_LIB"pure_quanta"
CDS_LMAN_SYM_OUTLINE"-150,150,150,-150"
NEEDS_NO_SIZE"TRUE"
PART_NUMBER"BAM138K0003";
"D1"
$PN"6"26;
"G1"
$PN"2"22;
"S1"
$PN"1"5;
%"UNIVERSAL_POWER"
"1","(-4875,3350)","0","pure_quanta_power","I24";
;
HDL_POWER"P3V3_AUX"
CDS_LIB"pure_quanta_power";
"A"3;
%"UNIVERSAL_POWER"
"1","(-4925,4525)","0","pure_quanta_power","I26";
;
HDL_POWER"P3V3_AUX"
CDS_LIB"pure_quanta_power";
"A"4;
%"MOSFET_NCH_DUAL"
"2","(-3200,4125)","0","pure_quanta","I27";
;
LOCATION"Q81"
SEC"2"
MATERIAL"IC"
VALUE"PJT138K"
PART_TYPE"SMLF"
CDS_LMAN_SYM_OUTLINE"-150,150,150,-150"
NEEDS_NO_SIZE"TRUE"
CDS_LIB"pure_quanta"
SEC_TYPE""
PART_NUMBER"BAM138K0003";
"S2"
$PN"4"6;
"G2"
$PN"5"27;
"D2"
$PN"3"24;
%"UNIVERSAL_GND"
"1","(-3150,2525)","0","pure_quanta_power","I28";
;
CDS_LIB"pure_quanta_power"
HDL_POWER"GND";
"A"5;
%"UNIVERSAL_GND"
"1","(-3150,3775)","0","pure_quanta_power","I29";
;
CDS_LIB"pure_quanta_power"
HDL_POWER"GND";
"A"6;
%"MOSFET_NCH_DUAL"
"2","(-7975,1575)","0","pure_quanta","I3";
;
LOCATION"Q80"
SEC"2"
VALUE"PJT138K"
MATERIAL"IC"
PART_TYPE"SMLF"
CDS_LMAN_SYM_OUTLINE"-150,150,150,-150"
NEEDS_NO_SIZE"TRUE"
CDS_LIB"pure_quanta"
SEC_TYPE""
PART_NUMBER"BAM138K0003";
"S2"
$PN"4"10;
"G2"
$PN"5"34;
"D2"
$PN"3"35;
%"Q_LED"
"1","(-2125,3150)","2","pure_quanta","I30";
;
LOCATION"D79"
$SEC"1"
CDS_SEC"1"
MANUF_PN"LTST-C281TBKT-5A"
PACK_TYPE"SMLF"
COLOR"LED_BLUE"
MATERIAL"IC"
NEEDS_NO_SIZE"TRUE"
CDS_LIB"pure_quanta"
PART_NUMBER"BEBL0172Z00";
"A"
$PN"A"25;
"C"
$PN"C"26;
%"UNIVERSAL_GND"
"1","(-3150,5100)","0","pure_quanta_power","I31";
;
CDS_LIB"pure_quanta_power"
HDL_POWER"GND";
"A"7;
%"Q_LED"
"1","(-2125,4400)","2","pure_quanta","I32";
;
LOCATION"D78"
$SEC"1"
CDS_SEC"1"
MANUF_PN"LTST-C281TBKT-5A"
MATERIAL"IC"
COLOR"LED_BLUE"
PACK_TYPE"SMLF"
NEEDS_NO_SIZE"TRUE"
CDS_LIB"pure_quanta"
PART_NUMBER"BEBL0172Z00";
"A"
$PN"A"29;
"C"
$PN"C"24;
%"UNIVERSAL_POWER"
"1","(-4900,5875)","0","pure_quanta_power","I33";
;
HDL_POWER"P3V3_AUX"
CDS_LIB"pure_quanta_power";
"A"8;
%"MOSFET_NCH_DUAL"
"1","(-3200,5450)","0","pure_quanta","I35";
;
LOCATION"Q81"
$SEC"1"
CDS_SEC"1"
MATERIAL"IC"
PART_TYPE"SMLF"
VALUE"PJT138K"
CDS_LIB"pure_quanta"
CDS_LMAN_SYM_OUTLINE"-150,150,150,-150"
NEEDS_NO_SIZE"TRUE"
PART_NUMBER"BAM138K0003";
"D1"
$PN"6"30;
"G1"
$PN"2"20;
"S1"
$PN"1"7;
%"Q_LED"
"1","(-2125,5725)","2","pure_quanta","I36";
;
LOCATION"D77"
$SEC"1"
CDS_SEC"1"
MANUF_PN"LTST-C281TBKT-5A"
PACK_TYPE"SMLF"
COLOR"LED_BLUE"
MATERIAL"IC"
CDS_LIB"pure_quanta"
NEEDS_NO_SIZE"TRUE"
PART_NUMBER"BEBL0172Z00";
"A"
$PN"A"31;
"C"
$PN"C"30;
%"Q_RES"
"1","(-825,3150)","0","pure_quanta","I37";
;
LOCATION"R3091"
$SEC"1"
CDS_SEC"1"
VALUE"130"
TOLERANCE"1%"
MATERIAL"CHIP"
WATTAGE"1/16W"
PACK_TYPE"0402LF"
CDS_LIB"pure_quanta"
PART_NUMBER"CS11302FB03";
"B"
$PN"2"9;
"A"
$PN"1"25;
%"Q_RES"
"1","(-825,4400)","0","pure_quanta","I38";
;
LOCATION"R3090"
$SEC"1"
CDS_SEC"1"
VALUE"130"
TOLERANCE"1%"
MATERIAL"CHIP"
WATTAGE"1/16W"
PACK_TYPE"0402LF"
CDS_LIB"pure_quanta"
PART_NUMBER"CS11302FB03";
"B"
$PN"2"11;
"A"
$PN"1"29;
%"UNIVERSAL_POWER"
"1","(-150,3300)","0","pure_quanta_power","I39";
;
HDL_POWER"P3V3_AUX"
CDS_LIB"pure_quanta_power";
"A"9;
%"UNIVERSAL_GND"
"1","(-7925,1225)","0","pure_quanta_power","I4";
;
CDS_LIB"pure_quanta_power"
HDL_POWER"GND";
"A"10;
%"UNIVERSAL_POWER"
"1","(-175,4550)","0","pure_quanta_power","I40";
;
HDL_POWER"P3V3_AUX"
CDS_LIB"pure_quanta_power";
"A"11;
%"Q_RES"
"1","(-800,5725)","0","pure_quanta","I41";
;
LOCATION"R3092"
$SEC"1"
CDS_SEC"1"
VALUE"130"
TOLERANCE"1%"
MATERIAL"CHIP"
WATTAGE"1/16W"
PACK_TYPE"0402LF"
CDS_LIB"pure_quanta"
PART_NUMBER"CS11302FB03";
"B"
$PN"2"12;
"A"
$PN"1"31;
%"UNIVERSAL_POWER"
"1","(-200,5900)","0","pure_quanta_power","I42";
;
HDL_POWER"P3V3_AUX"
CDS_LIB"pure_quanta_power";
"A"12;
%"MOSFET_NCH_DUAL"
"2","(-3175,1900)","0","pure_quanta","I43";
;
LOCATION"Q83"
$SEC"2"
CDS_SEC"2"
MATERIAL"IC"
VALUE"PJT138K"
PART_TYPE"SMLF"
CDS_LIB"pure_quanta"
NEEDS_NO_SIZE"TRUE"
CDS_LMAN_SYM_OUTLINE"-150,150,150,-150"
PART_NUMBER"BAM138K0003";
"S2"
$PN"4"17;
"G2"
$PN"5"21;
"D2"
$PN"3"18;
%"UNIVERSAL_GND"
"1","(-7925,2550)","0","pure_quanta_power","I5";
;
CDS_LIB"pure_quanta_power"
HDL_POWER"GND";
"A"13;
%"MOSFET_NCH_DUAL"
"1","(-7975,2900)","0","pure_quanta","I6";
;
LOCATION"Q80"
$SEC"1"
CDS_SEC"1"
MATERIAL"IC"
PART_TYPE"SMLF"
VALUE"PJT138K"
CDS_LIB"pure_quanta"
CDS_LMAN_SYM_OUTLINE"-150,150,150,-150"
NEEDS_NO_SIZE"TRUE"
PART_NUMBER"BAM138K0003";
"D1"
$PN"6"33;
"G1"
$PN"2"37;
"S1"
$PN"1"13;
%"MOSFET_NCH_DUAL"
"2","(-7975,4125)","0","pure_quanta","I8";
;
LOCATION"Q79"
SEC"2"
MATERIAL"IC"
VALUE"PJT138K"
PART_TYPE"SMLF"
CDS_LMAN_SYM_OUTLINE"-150,150,150,-150"
NEEDS_NO_SIZE"TRUE"
CDS_LIB"pure_quanta"
SEC_TYPE""
PART_NUMBER"BAM138K0003";
"S2"
$PN"4"14;
"G2"
$PN"5"36;
"D2"
$PN"3"15;
%"UNIVERSAL_GND"
"1","(-7925,3775)","0","pure_quanta_power","I9";
;
CDS_LIB"pure_quanta_power"
HDL_POWER"GND";
"A"14;
END.
